# T6G (Grand Teton) — schematic netlist excerpt (pin names and nets, part order shuffled) for the footprints in the layout excerpt that follows; sources: Cadence DE-HDL packaged netlist, KiCad conversion of 04192023_DAF0TMB3IC0_F0TG_MB_C_brd_V02_OCP.brd

C6717  Q_CAP_DIFFBUS  DIFF BUS_0.22UF 6.3V 20% X6S  pkg C0201  page 341 : \1\ = P5E_CPU1_P2_TX_BUF_C_DP<12> ; \2\ = P5E_CPU1_P2_TX_BUF_DP<12>

U40  SN74LVC2G07DCKR  IC  pkg SMLF  page 78
  \1a\  = PWRGD_CPU1_PWROK
  GND  = GND
  \2a\  = PWRGD_CPU1_PWROK
  \2y\  = PVDDCR_CPU1_P1_RESET_N
  VCC  = P1V8_AUX
  \1y\  = PVDDCR_CPU0_P1_RESET_N

R4420  Q_RES  49.9 1% EMPTY  pkg 0402LF  page 234 : A = USB2_HOST_BMC_B_DN ; B = GND

(kicad_pcb
	(version 20260206)
	(generator "pcbnew")
	(generator_version "10.0")
	(general
		(thickness 1.6)
		(legacy_teardrops no)
	)
	(paper "A4")
	(title_block
		(title "04192023_DAF0TMB3IC0_F0TG_MB_C_brd_V02_OCP.brd")
		(comment 1 "Grand Teton / footprints 140-142 of 8354")
	)
	(layers
		(0 "F.Cu" signal "TOP")
		(4 "In1.Cu" signal "GND")
		(6 "In2.Cu" signal "IN1")
		(8 "In3.Cu" signal "GND1")
		(10 "In4.Cu" signal "IN2")
		(12 "In5.Cu" signal "GND2")
		(14 "In6.Cu" signal "IN3")
		(16 "In7.Cu" signal "GND3")
		(18 "In8.Cu" signal "VCC")
		(20 "In9.Cu" signal "VCC1")
		(22 "In10.Cu" signal "GND4")
		(24 "In11.Cu" signal "IN4")
		(26 "In12.Cu" signal "GND5")
		(28 "In13.Cu" signal "IN5")
		(30 "In14.Cu" signal "GND6")
		(32 "In15.Cu" signal "IN6")
		(34 "In16.Cu" signal "GND7")
		(2 "B.Cu" signal "BOTTOM")
		(9 "F.Adhes" user "F.Adhesive")
		(11 "B.Adhes" user "B.Adhesive")
		(13 "F.Paste" user "Package Geometry/Pastemask Top")
		(15 "B.Paste" user "Package Geometry/Pastemask Bottom")
		(5 "F.SilkS" user "Ref Des/Silkscreen Top")
		(7 "B.SilkS" user "Ref Des/Silkscreen Bottom")
		(1 "F.Mask" user "Board Geometry/Soldermask Top")
		(3 "B.Mask" user "Board Geometry/Soldermask Bottom")
		(17 "Dwgs.User" user "User.Drawings")
		(19 "Cmts.User" user "User.Comments")
		(21 "Eco1.User" user "User.Eco1")
		(23 "Eco2.User" user "User.Eco2")
		(25 "Edge.Cuts" user "Board Geometry/Outline")
		(27 "Margin" user)
		(31 "F.CrtYd" user "Package Geometry/Place Bound Top")
		(29 "B.CrtYd" user "Package Geometry/Place Bound Bottom")
		(35 "F.Fab" user "Ref Des/Assembly Top")
		(33 "B.Fab" user "Ref Des/Assembly Bottom")
	)
	(footprint ""
		(layer "F.Cu")
		(at 83.40725 -141.308836 90)
		(property "Reference" "U40"
			(at 1.051814 -2.801112 90)
			(unlocked yes)
			(layer "F.SilkS")
			(effects
				(font
					(size 0.7874 0.5842)
					(thickness 0.1524)
				)
			)
		)
		(property "Value" ""
			(at 0 0 90)
			(layer "F.Fab")
			(effects
				(font
					(size 1.27 1.27)
				)
			)
		)
		(duplicate_pad_numbers_are_jumpers no)
		(fp_line
			(start 1.7272 -1.1176)
			(end 0.254 -1.1176)
			(stroke
				(width 0.1524)
				(type default)
			)
			(layer "F.SilkS")
		)
		(fp_line
			(start 1.7272 -1.1176)
			(end 1.7272 1.1176)
			(stroke
				(width 0.1524)
				(type default)
			)
			(layer "F.SilkS")
		)
		(fp_line
			(start 0.254 -1.1176)
			(end 0 -0.7366)
			(stroke
				(width 0.1524)
				(type default)
			)
			(layer "F.SilkS")
		)
		(fp_line
			(start -0.254 -1.1176)
			(end -1.7272 -1.1176)
			(stroke
				(width 0.1524)
				(type default)
			)
			(layer "F.SilkS")
		)
		(fp_line
			(start 0 -0.7366)
			(end -0.254 -1.1176)
			(stroke
				(width 0.1524)
				(type default)
			)
			(layer "F.SilkS")
		)
		(fp_line
			(start 1.7272 1.1176)
			(end -1.7272 1.1176)
			(stroke
				(width 0.1524)
				(type default)
			)
			(layer "F.SilkS")
		)
		(fp_line
			(start -1.7272 1.1176)
			(end -1.7272 -1.1176)
			(stroke
				(width 0.1524)
				(type default)
			)
			(layer "F.SilkS")
		)
		(fp_poly
			(pts
				(xy -0.618998 -2.367788) (xy -0.999998 -1.605788) (xy -1.380998 -2.367788)
			)
			(stroke
				(width 0)
				(type default)
			)
			(fill yes)
			(layer "F.SilkS")
		)
		(fp_line
			(start 1.5748 -1.1176)
			(end -1.5748 -1.1176)
			(stroke
				(width 0.1)
				(type default)
			)
			(layer "F.Fab")
		)
		(fp_line
			(start -1.5748 -1.1176)
			(end -1.5748 1.1176)
			(stroke
				(width 0.1)
				(type default)
			)
			(layer "F.Fab")
		)
		(fp_line
			(start 1.5748 1.1176)
			(end 1.5748 -1.1176)
			(stroke
				(width 0.1)
				(type default)
			)
			(layer "F.Fab")
		)
		(fp_line
			(start -1.5748 1.1176)
			(end 1.5748 1.1176)
			(stroke
				(width 0.1)
				(type default)
			)
			(layer "F.Fab")
		)
		(fp_poly
			(pts
				(xy -1.9558 -0.649986) (xy -2.7178 -0.268986) (xy -2.7178 -1.030986)
			)
			(stroke
				(width 0)
				(type default)
			)
			(fill yes)
			(layer "F.Fab")
		)
		(pad "1" smd rect
			(at -0.999998 -0.649986)
			(size 0.3556 1.1176)
			(layers "F.Cu" "F.Mask" "F.Paste")
			(net "PWRGD_CPU1_PWROK")
		)
		(pad "2" smd rect
			(at -0.999998 0)
			(size 0.3556 1.1176)
			(layers "F.Cu" "F.Mask" "F.Paste")
			(net "GND")
		)
		(pad "3" smd rect
			(at -0.999998 0.649986)
			(size 0.3556 1.1176)
			(layers "F.Cu" "F.Mask" "F.Paste")
			(net "PWRGD_CPU1_PWROK")
		)
		(pad "4" smd rect
			(at 0.999998 0.649986)
			(size 0.3556 1.1176)
			(layers "F.Cu" "F.Mask" "F.Paste")
			(net "PVDDCR_CPU1_P1_RESET_N")
		)
		(pad "5" smd rect
			(at 0.999998 0)
			(size 0.3556 1.1176)
			(layers "F.Cu" "F.Mask" "F.Paste")
			(net "P1V8_AUX")
		)
		(pad "6" smd rect
			(at 0.999998 -0.649986)
			(size 0.3556 1.1176)
			(layers "F.Cu" "F.Mask" "F.Paste")
			(net "PVDDCR_CPU0_P1_RESET_N")
		)
	)
	(footprint ""
		(layer "F.Cu")
		(at 152.541986 -408.517344 -90)
		(property "Reference" "C6717"
			(at 0 0 270)
			(layer "F.SilkS")
			(hide yes)
			(effects
				(font
					(size 1.27 1.27)
				)
			)
		)
		(property "Value" ""
			(at 0 0 270)
			(layer "F.Fab")
			(effects
				(font
					(size 1.27 1.27)
				)
			)
		)
		(duplicate_pad_numbers_are_jumpers no)
		(fp_line
			(start -0.299974 0.150114)
			(end -0.299974 -0.150114)
			(stroke
				(width 0.1)
				(type default)
			)
			(layer "F.Fab")
		)
		(fp_line
			(start 0.299974 0.150114)
			(end -0.299974 0.150114)
			(stroke
				(width 0.1)
				(type default)
			)
			(layer "F.Fab")
		)
		(fp_line
			(start -0.299974 -0.150114)
			(end 0.299974 -0.150114)
			(stroke
				(width 0.1)
				(type default)
			)
			(layer "F.Fab")
		)
		(fp_line
			(start 0.299974 -0.150114)
			(end 0.299974 0.150114)
			(stroke
				(width 0.1)
				(type default)
			)
			(layer "F.Fab")
		)
		(pad "1" smd rect
			(at -0.2667 0 270)
			(size 0.3048 0.381)
			(layers "F.Cu" "F.Mask" "F.Paste")
			(net "P5E_CPU1_P2_TX_BUF_C_DP<12>")
		)
		(pad "2" smd rect
			(at 0.2667 0 270)
			(size 0.3048 0.381)
			(layers "F.Cu" "F.Mask" "F.Paste")
			(net "P5E_CPU1_P2_TX_BUF_DP<12>")
		)
	)
	(footprint ""
		(layer "F.Cu")
		(at 17.658842 -105.537762 90)
		(property "Reference" "R4420"
			(at 0 0 90)
			(layer "F.SilkS")
			(hide yes)
			(effects
				(font
					(size 1.27 1.27)
				)
			)
		)
		(property "Value" ""
			(at 0 0 90)
			(layer "F.Fab")
			(effects
				(font
					(size 1.27 1.27)
				)
			)
		)
		(duplicate_pad_numbers_are_jumpers no)
		(fp_line
			(start 0.7874 -0.4064)
			(end 0.7874 0.4064)
			(stroke
				(width 0.1524)
				(type default)
			)
			(layer "F.SilkS")
		)
		(fp_line
			(start -0.7874 -0.4064)
			(end 0.7874 -0.4064)
			(stroke
				(width 0.1524)
				(type default)
			)
			(layer "F.SilkS")
		)
		(fp_line
			(start 0.7874 0.4064)
			(end -0.7874 0.4064)
			(stroke
				(width 0.1524)
				(type default)
			)
			(layer "F.SilkS")
		)
		(fp_line
			(start -0.7874 0.4064)
			(end -0.7874 -0.4064)
			(stroke
				(width 0.1524)
				(type default)
			)
			(layer "F.SilkS")
		)
		(fp_line
			(start -0.12065 -0.305054)
			(end -0.12065 -0.2794)
			(stroke
				(width 0.1)
				(type default)
			)
			(layer "F.Fab")
		)
		(fp_line
			(start -0.67945 -0.305054)
			(end -0.12065 -0.305054)
			(stroke
				(width 0.1)
				(type default)
			)
			(layer "F.Fab")
		)
		(fp_line
			(start 0.67945 -0.3048)
			(end 0.67945 0.3048)
			(stroke
				(width 0.1)
				(type default)
			)
			(layer "F.Fab")
		)
		(fp_line
			(start 0.12065 -0.3048)
			(end 0.67945 -0.3048)
			(stroke
				(width 0.1)
				(type default)
			)
			(layer "F.Fab")
		)
		(fp_line
			(start 0.12065 -0.2794)
			(end 0.12065 -0.3048)
			(stroke
				(width 0.1)
				(type default)
			)
			(layer "F.Fab")
		)
		(fp_line
			(start -0.12065 -0.2794)
			(end 0.12065 -0.2794)
			(stroke
				(width 0.1)
				(type default)
			)
			(layer "F.Fab")
		)
		(fp_line
			(start 0.120396 0.2794)
			(end -0.12065 0.2794)
			(stroke
				(width 0.1)
				(type default)
			)
			(layer "F.Fab")
		)
		(fp_line
			(start -0.12065 0.2794)
			(end -0.12065 0.3048)
			(stroke
				(width 0.1)
				(type default)
			)
			(layer "F.Fab")
		)
		(fp_line
			(start 0.67945 0.3048)
			(end 0.120396 0.3048)
			(stroke
				(width 0.1)
				(type default)
			)
			(layer "F.Fab")
		)
		(fp_line
			(start 0.120396 0.3048)
			(end 0.120396 0.2794)
			(stroke
				(width 0.1)
				(type default)
			)
			(layer "F.Fab")
		)
		(fp_line
			(start -0.12065 0.3048)
			(end -0.67945 0.3048)
			(stroke
				(width 0.1)
				(type default)
			)
			(layer "F.Fab")
		)
		(fp_line
			(start -0.67945 0.3048)
			(end -0.67945 -0.305054)
			(stroke
				(width 0.1)
				(type default)
			)
			(layer "F.Fab")
		)
		(pad "1" smd circle
			(at -0.40005 0 90)
			(size 0 0)
			(layers "F.Cu" "F.Mask" "F.Paste")
			(net "USB2_HOST_BMC_B_DN")
		)
		(pad "2" smd circle
			(at 0.40005 0 90)
			(size 0 0)
			(layers "F.Cu" "F.Mask" "F.Paste")
			(net "GND")
		)
	)
)
